# T6G (Grand Teton) — schematic netlist excerpt (pin names and nets, part order shuffled) for the footprints in the layout excerpt that follows; sources: Cadence DE-HDL packaged netlist, KiCad conversion of 04192023_DAF0TMB3IC0_F0TG_MB_C_brd_V02_OCP.brd

R8039  Q_RES  10K 1% CHIP  pkg 0402LF  page 98 : A = P3V3_AUX ; B = PWRGD_CHAF_CPU1
R1735  Q_RES  10K 1% EMPTY  pkg 0402LF  page 171 : A = JTAG_SCM_TCK ; B = GND

(kicad_pcb
	(version 20260206)
	(generator "pcbnew")
	(generator_version "10.0")
	(general
		(thickness 1.6)
		(legacy_teardrops no)
	)
	(paper "A4")
	(title_block
		(title "04192023_DAF0TMB3IC0_F0TG_MB_C_brd_V02_OCP.brd")
		(comment 1 "Grand Teton / footprints 332-333 of 8354")
	)
	(layers
		(0 "F.Cu" signal "TOP")
		(4 "In1.Cu" signal "GND")
		(6 "In2.Cu" signal "IN1")
		(8 "In3.Cu" signal "GND1")
		(10 "In4.Cu" signal "IN2")
		(12 "In5.Cu" signal "GND2")
		(14 "In6.Cu" signal "IN3")
		(16 "In7.Cu" signal "GND3")
		(18 "In8.Cu" signal "VCC")
		(20 "In9.Cu" signal "VCC1")
		(22 "In10.Cu" signal "GND4")
		(24 "In11.Cu" signal "IN4")
		(26 "In12.Cu" signal "GND5")
		(28 "In13.Cu" signal "IN5")
		(30 "In14.Cu" signal "GND6")
		(32 "In15.Cu" signal "IN6")
		(34 "In16.Cu" signal "GND7")
		(2 "B.Cu" signal "BOTTOM")
		(9 "F.Adhes" user "F.Adhesive")
		(11 "B.Adhes" user "B.Adhesive")
		(13 "F.Paste" user "Package Geometry/Pastemask Top")
		(15 "B.Paste" user "Package Geometry/Pastemask Bottom")
		(5 "F.SilkS" user "Ref Des/Silkscreen Top")
		(7 "B.SilkS" user "Ref Des/Silkscreen Bottom")
		(1 "F.Mask" user "Board Geometry/Soldermask Top")
		(3 "B.Mask" user "Board Geometry/Soldermask Bottom")
		(17 "Dwgs.User" user "User.Drawings")
		(19 "Cmts.User" user "User.Comments")
		(21 "Eco1.User" user "User.Eco1")
		(23 "Eco2.User" user "User.Eco2")
		(25 "Edge.Cuts" user "Board Geometry/Outline")
		(27 "Margin" user)
		(31 "F.CrtYd" user "Package Geometry/Place Bound Top")
		(29 "B.CrtYd" user "Package Geometry/Place Bound Bottom")
		(35 "F.Fab" user "Ref Des/Assembly Top")
		(33 "B.Fab" user "Ref Des/Assembly Bottom")
	)
	(footprint ""
		(layer "F.Cu")
		(at 118.718584 -58.868056)
		(property "Reference" "R1735"
			(at 0 0 0)
			(layer "F.SilkS")
			(hide yes)
			(effects
				(font
					(size 1.27 1.27)
				)
			)
		)
		(property "Value" ""
			(at 0 0 0)
			(layer "F.Fab")
			(effects
				(font
					(size 1.27 1.27)
				)
			)
		)
		(duplicate_pad_numbers_are_jumpers no)
		(fp_line
			(start -0.7874 -0.4064)
			(end 0.7874 -0.4064)
			(stroke
				(width 0.1524)
				(type default)
			)
			(layer "F.SilkS")
		)
		(fp_line
			(start -0.7874 0.4064)
			(end -0.7874 -0.4064)
			(stroke
				(width 0.1524)
				(type default)
			)
			(layer "F.SilkS")
		)
		(fp_line
			(start 0.7874 -0.4064)
			(end 0.7874 0.4064)
			(stroke
				(width 0.1524)
				(type default)
			)
			(layer "F.SilkS")
		)
		(fp_line
			(start 0.7874 0.4064)
			(end -0.7874 0.4064)
			(stroke
				(width 0.1524)
				(type default)
			)
			(layer "F.SilkS")
		)
		(fp_line
			(start -0.67945 -0.305054)
			(end -0.12065 -0.305054)
			(stroke
				(width 0.1)
				(type default)
			)
			(layer "F.Fab")
		)
		(fp_line
			(start -0.67945 0.3048)
			(end -0.67945 -0.305054)
			(stroke
				(width 0.1)
				(type default)
			)
			(layer "F.Fab")
		)
		(fp_line
			(start -0.12065 -0.305054)
			(end -0.12065 -0.2794)
			(stroke
				(width 0.1)
				(type default)
			)
			(layer "F.Fab")
		)
		(fp_line
			(start -0.12065 -0.2794)
			(end 0.12065 -0.2794)
			(stroke
				(width 0.1)
				(type default)
			)
			(layer "F.Fab")
		)
		(fp_line
			(start -0.12065 0.2794)
			(end -0.12065 0.3048)
			(stroke
				(width 0.1)
				(type default)
			)
			(layer "F.Fab")
		)
		(fp_line
			(start -0.12065 0.3048)
			(end -0.67945 0.3048)
			(stroke
				(width 0.1)
				(type default)
			)
			(layer "F.Fab")
		)
		(fp_line
			(start 0.120396 0.2794)
			(end -0.12065 0.2794)
			(stroke
				(width 0.1)
				(type default)
			)
			(layer "F.Fab")
		)
		(fp_line
			(start 0.120396 0.3048)
			(end 0.120396 0.2794)
			(stroke
				(width 0.1)
				(type default)
			)
			(layer "F.Fab")
		)
		(fp_line
			(start 0.12065 -0.3048)
			(end 0.67945 -0.3048)
			(stroke
				(width 0.1)
				(type default)
			)
			(layer "F.Fab")
		)
		(fp_line
			(start 0.12065 -0.2794)
			(end 0.12065 -0.3048)
			(stroke
				(width 0.1)
				(type default)
			)
			(layer "F.Fab")
		)
		(fp_line
			(start 0.67945 -0.3048)
			(end 0.67945 0.3048)
			(stroke
				(width 0.1)
				(type default)
			)
			(layer "F.Fab")
		)
		(fp_line
			(start 0.67945 0.3048)
			(end 0.120396 0.3048)
			(stroke
				(width 0.1)
				(type default)
			)
			(layer "F.Fab")
		)
		(pad "1" smd circle
			(at -0.40005 0)
			(size 0 0)
			(layers "F.Cu" "F.Mask" "F.Paste")
			(net "JTAG_SCM_TCK")
		)
		(pad "2" smd circle
			(at 0.40005 0)
			(size 0 0)
			(layers "F.Cu" "F.Mask" "F.Paste")
			(net "GND")
		)
	)
	(footprint ""
		(layer "F.Cu")
		(at 145.161 -120.777)
		(property "Reference" "R8039"
			(at 0 0 0)
			(layer "F.SilkS")
			(hide yes)
			(effects
				(font
					(size 1.27 1.27)
				)
			)
		)
		(property "Value" ""
			(at 0 0 0)
			(layer "F.Fab")
			(effects
				(font
					(size 1.27 1.27)
				)
			)
		)
		(duplicate_pad_numbers_are_jumpers no)
		(fp_line
			(start -0.7874 -0.4064)
			(end 0.7874 -0.4064)
			(stroke
				(width 0.1524)
				(type default)
			)
			(layer "F.SilkS")
		)
		(fp_line
			(start -0.7874 0.4064)
			(end -0.7874 -0.4064)
			(stroke
				(width 0.1524)
				(type default)
			)
			(layer "F.SilkS")
		)
		(fp_line
			(start 0.7874 -0.4064)
			(end 0.7874 0.4064)
			(stroke
				(width 0.1524)
				(type default)
			)
			(layer "F.SilkS")
		)
		(fp_line
			(start 0.7874 0.4064)
			(end -0.7874 0.4064)
			(stroke
				(width 0.1524)
				(type default)
			)
			(layer "F.SilkS")
		)
		(fp_line
			(start -0.67945 -0.305054)
			(end -0.12065 -0.305054)
			(stroke
				(width 0.1)
				(type default)
			)
			(layer "F.Fab")
		)
		(fp_line
			(start -0.67945 0.3048)
			(end -0.67945 -0.305054)
			(stroke
				(width 0.1)
				(type default)
			)
			(layer "F.Fab")
		)
		(fp_line
			(start -0.12065 -0.305054)
			(end -0.12065 -0.2794)
			(stroke
				(width 0.1)
				(type default)
			)
			(layer "F.Fab")
		)
		(fp_line
			(start -0.12065 -0.2794)
			(end 0.12065 -0.2794)
			(stroke
				(width 0.1)
				(type default)
			)
			(layer "F.Fab")
		)
		(fp_line
			(start -0.12065 0.2794)
			(end -0.12065 0.3048)
			(stroke
				(width 0.1)
				(type default)
			)
			(layer "F.Fab")
		)
		(fp_line
			(start -0.12065 0.3048)
			(end -0.67945 0.3048)
			(stroke
				(width 0.1)
				(type default)
			)
			(layer "F.Fab")
		)
		(fp_line
			(start 0.120396 0.2794)
			(end -0.12065 0.2794)
			(stroke
				(width 0.1)
				(type default)
			)
			(layer "F.Fab")
		)
		(fp_line
			(start 0.120396 0.3048)
			(end 0.120396 0.2794)
			(stroke
				(width 0.1)
				(type default)
			)
			(layer "F.Fab")
		)
		(fp_line
			(start 0.12065 -0.3048)
			(end 0.67945 -0.3048)
			(stroke
				(width 0.1)
				(type default)
			)
			(layer "F.Fab")
		)
		(fp_line
			(start 0.12065 -0.2794)
			(end 0.12065 -0.3048)
			(stroke
				(width 0.1)
				(type default)
			)
			(layer "F.Fab")
		)
		(fp_line
			(start 0.67945 -0.3048)
			(end 0.67945 0.3048)
			(stroke
				(width 0.1)
				(type default)
			)
			(layer "F.Fab")
		)
		(fp_line
			(start 0.67945 0.3048)
			(end 0.120396 0.3048)
			(stroke
				(width 0.1)
				(type default)
			)
			(layer "F.Fab")
		)
		(pad "1" smd circle
			(at -0.40005 0)
			(size 0 0)
			(layers "F.Cu" "F.Mask" "F.Paste")
			(net "P3V3_AUX")
		)
		(pad "2" smd circle
			(at 0.40005 0)
			(size 0 0)
			(layers "F.Cu" "F.Mask" "F.Paste")
			(net "PWRGD_CHAF_CPU1")
		)
	)
)
